 FILE_TYPE = MACRO_DRAWING;
SET DECIMAL;
GRID   .100 5
SET COLOR_WIRE MONO            ;
SET COLOR_PROP MONO            ;
SET COLOR_DOT MONO            ;
SET COLOR_ARC MONO            ;
SET COLOR_BODY MONO            ;
SET COLOR_NOTE MONO            ;
FORCEADD DEFINE..1
(1200 3150);
PAINT GREEN           (1200 3150);
FORCEPROP 1 LAST X_FIRST 0
J 0
(1025 3050);
DISPLAY B (1025 3050);
PAINT GREEN           (1025 3050);
FORCEPROP 1 LAST X_STEP SIZE
J 0
(975 2950);
DISPLAY B (975 2950);
PAINT GREEN           (975 2950);
FORCEADD DRAWING..1
(2500 3150);
PAINT GREEN           (2500 3150);
FORCEPROP 1 LAST LAST_MODIFIED Wed Dec 10 11:30:45 1986
J 0
(2300 2850);
DISPLAY B (2300 2850);
PAINT GREEN           (2300 2850);
FORCEPROP 2 LAST TITLE OFFPAGE
J 0
(2300 3050);
DISPLAY B (2300 3050);
PAINT BROWN           (2300 3050);
FORCEPROP 2 LAST ABBREV OFP
J 0
(2300 3000);
DISPLAY B (2300 3000);
PAINT BROWN           (2300 3000);
QUIT
